# T6G (Grand Teton) — schematic netlist excerpt (pin names and nets, part order shuffled) for the footprints in the layout excerpt that follows; sources: Cadence DE-HDL packaged netlist, KiCad conversion of 04192023_DAF0TMB3IC0_F0TG_MB_C_brd_V02_OCP.brd

R1295  Q_RES  0 5% CHIP  pkg 0402LF  page 159 : A = I3C_SPD_DDRGL_CPU1_SCL ; B = I3C_SPD_DDRGL_CPU1_LVC1_SCL
C5010  Q_CAP  1000PF 50V 5% X7R  pkg 0402  page 224 : A = PVDD11_S3_P1_PMALERT ; B = GND
H22  HOLE  EMPTY  pkg TH  page 230 : \1\ = GND

(kicad_pcb
	(version 20260206)
	(generator "pcbnew")
	(generator_version "10.0")
	(general
		(thickness 1.6)
		(legacy_teardrops no)
	)
	(paper "A4")
	(title_block
		(title "04192023_DAF0TMB3IC0_F0TG_MB_C_brd_V02_OCP.brd")
		(comment 1 "Grand Teton / footprints 716-718 of 8354")
	)
	(layers
		(0 "F.Cu" signal "TOP")
		(4 "In1.Cu" signal "GND")
		(6 "In2.Cu" signal "IN1")
		(8 "In3.Cu" signal "GND1")
		(10 "In4.Cu" signal "IN2")
		(12 "In5.Cu" signal "GND2")
		(14 "In6.Cu" signal "IN3")
		(16 "In7.Cu" signal "GND3")
		(18 "In8.Cu" signal "VCC")
		(20 "In9.Cu" signal "VCC1")
		(22 "In10.Cu" signal "GND4")
		(24 "In11.Cu" signal "IN4")
		(26 "In12.Cu" signal "GND5")
		(28 "In13.Cu" signal "IN5")
		(30 "In14.Cu" signal "GND6")
		(32 "In15.Cu" signal "IN6")
		(34 "In16.Cu" signal "GND7")
		(2 "B.Cu" signal "BOTTOM")
		(9 "F.Adhes" user "F.Adhesive")
		(11 "B.Adhes" user "B.Adhesive")
		(13 "F.Paste" user "Package Geometry/Pastemask Top")
		(15 "B.Paste" user "Package Geometry/Pastemask Bottom")
		(5 "F.SilkS" user "Ref Des/Silkscreen Top")
		(7 "B.SilkS" user "Ref Des/Silkscreen Bottom")
		(1 "F.Mask" user "Board Geometry/Soldermask Top")
		(3 "B.Mask" user "Board Geometry/Soldermask Bottom")
		(17 "Dwgs.User" user "User.Drawings")
		(19 "Cmts.User" user "User.Comments")
		(21 "Eco1.User" user "User.Eco1")
		(23 "Eco2.User" user "User.Eco2")
		(25 "Edge.Cuts" user "Board Geometry/Outline")
		(27 "Margin" user)
		(31 "F.CrtYd" user "Package Geometry/Place Bound Top")
		(29 "B.CrtYd" user "Package Geometry/Place Bound Bottom")
		(35 "F.Fab" user "Ref Des/Assembly Top")
		(33 "B.Fab" user "Ref Des/Assembly Bottom")
	)
	(footprint ""
		(layer "F.Cu")
		(at 181.388766 -168.317418 -90)
		(property "Reference" "R1295"
			(at 0 0 270)
			(layer "F.SilkS")
			(hide yes)
			(effects
				(font
					(size 1.27 1.27)
				)
			)
		)
		(property "Value" ""
			(at 0 0 270)
			(layer "F.Fab")
			(effects
				(font
					(size 1.27 1.27)
				)
			)
		)
		(duplicate_pad_numbers_are_jumpers no)
		(fp_line
			(start -0.7874 0.4064)
			(end -0.7874 -0.4064)
			(stroke
				(width 0.1524)
				(type default)
			)
			(layer "F.SilkS")
		)
		(fp_line
			(start 0.7874 0.4064)
			(end -0.7874 0.4064)
			(stroke
				(width 0.1524)
				(type default)
			)
			(layer "F.SilkS")
		)
		(fp_line
			(start -0.7874 -0.4064)
			(end 0.7874 -0.4064)
			(stroke
				(width 0.1524)
				(type default)
			)
			(layer "F.SilkS")
		)
		(fp_line
			(start 0.7874 -0.4064)
			(end 0.7874 0.4064)
			(stroke
				(width 0.1524)
				(type default)
			)
			(layer "F.SilkS")
		)
		(fp_line
			(start -0.67945 0.3048)
			(end -0.67945 -0.305054)
			(stroke
				(width 0.1)
				(type default)
			)
			(layer "F.Fab")
		)
		(fp_line
			(start -0.12065 0.3048)
			(end -0.67945 0.3048)
			(stroke
				(width 0.1)
				(type default)
			)
			(layer "F.Fab")
		)
		(fp_line
			(start 0.120396 0.3048)
			(end 0.120396 0.2794)
			(stroke
				(width 0.1)
				(type default)
			)
			(layer "F.Fab")
		)
		(fp_line
			(start 0.67945 0.3048)
			(end 0.120396 0.3048)
			(stroke
				(width 0.1)
				(type default)
			)
			(layer "F.Fab")
		)
		(fp_line
			(start -0.12065 0.2794)
			(end -0.12065 0.3048)
			(stroke
				(width 0.1)
				(type default)
			)
			(layer "F.Fab")
		)
		(fp_line
			(start 0.120396 0.2794)
			(end -0.12065 0.2794)
			(stroke
				(width 0.1)
				(type default)
			)
			(layer "F.Fab")
		)
		(fp_line
			(start -0.12065 -0.2794)
			(end 0.12065 -0.2794)
			(stroke
				(width 0.1)
				(type default)
			)
			(layer "F.Fab")
		)
		(fp_line
			(start 0.12065 -0.2794)
			(end 0.12065 -0.3048)
			(stroke
				(width 0.1)
				(type default)
			)
			(layer "F.Fab")
		)
		(fp_line
			(start 0.12065 -0.3048)
			(end 0.67945 -0.3048)
			(stroke
				(width 0.1)
				(type default)
			)
			(layer "F.Fab")
		)
		(fp_line
			(start 0.67945 -0.3048)
			(end 0.67945 0.3048)
			(stroke
				(width 0.1)
				(type default)
			)
			(layer "F.Fab")
		)
		(fp_line
			(start -0.67945 -0.305054)
			(end -0.12065 -0.305054)
			(stroke
				(width 0.1)
				(type default)
			)
			(layer "F.Fab")
		)
		(fp_line
			(start -0.12065 -0.305054)
			(end -0.12065 -0.2794)
			(stroke
				(width 0.1)
				(type default)
			)
			(layer "F.Fab")
		)
		(pad "1" smd rect
			(at -0.40005 0 90)
			(size 0.4572 0.508)
			(layers "F.Cu" "F.Mask" "F.Paste")
			(net "I3C_SPD_DDRGL_CPU1_SCL")
		)
		(pad "2" smd rect
			(at 0.40005 0 90)
			(size 0.4572 0.508)
			(layers "F.Cu" "F.Mask" "F.Paste")
			(net "I3C_SPD_DDRGL_CPU1_LVC1_SCL")
		)
	)
	(footprint ""
		(layer "F.Cu")
		(at 157.677358 -353.245928 180)
		(property "Reference" "C5010"
			(at 0 0 180)
			(layer "F.SilkS")
			(hide yes)
			(effects
				(font
					(size 1.27 1.27)
				)
			)
		)
		(property "Value" ""
			(at 0 0 180)
			(layer "F.Fab")
			(effects
				(font
					(size 1.27 1.27)
				)
			)
		)
		(duplicate_pad_numbers_are_jumpers no)
		(fp_line
			(start 0.7874 0.4064)
			(end -0.7874 0.4064)
			(stroke
				(width 0.1524)
				(type default)
			)
			(layer "F.SilkS")
		)
		(fp_line
			(start 0.7874 -0.4064)
			(end 0.7874 0.4064)
			(stroke
				(width 0.1524)
				(type default)
			)
			(layer "F.SilkS")
		)
		(fp_line
			(start -0.7874 0.4064)
			(end -0.7874 -0.4064)
			(stroke
				(width 0.1524)
				(type default)
			)
			(layer "F.SilkS")
		)
		(fp_line
			(start -0.7874 -0.4064)
			(end 0.7874 -0.4064)
			(stroke
				(width 0.1524)
				(type default)
			)
			(layer "F.SilkS")
		)
		(fp_line
			(start 0.67945 0.3048)
			(end 0.120396 0.3048)
			(stroke
				(width 0.1)
				(type default)
			)
			(layer "F.Fab")
		)
		(fp_line
			(start 0.67945 -0.3048)
			(end 0.67945 0.3048)
			(stroke
				(width 0.1)
				(type default)
			)
			(layer "F.Fab")
		)
		(fp_line
			(start 0.12065 -0.2794)
			(end 0.12065 -0.3048)
			(stroke
				(width 0.1)
				(type default)
			)
			(layer "F.Fab")
		)
		(fp_line
			(start 0.12065 -0.3048)
			(end 0.67945 -0.3048)
			(stroke
				(width 0.1)
				(type default)
			)
			(layer "F.Fab")
		)
		(fp_line
			(start 0.120396 0.3048)
			(end 0.120396 0.2794)
			(stroke
				(width 0.1)
				(type default)
			)
			(layer "F.Fab")
		)
		(fp_line
			(start 0.120396 0.2794)
			(end -0.12065 0.2794)
			(stroke
				(width 0.1)
				(type default)
			)
			(layer "F.Fab")
		)
		(fp_line
			(start -0.12065 0.3048)
			(end -0.67945 0.3048)
			(stroke
				(width 0.1)
				(type default)
			)
			(layer "F.Fab")
		)
		(fp_line
			(start -0.12065 0.2794)
			(end -0.12065 0.3048)
			(stroke
				(width 0.1)
				(type default)
			)
			(layer "F.Fab")
		)
		(fp_line
			(start -0.12065 -0.2794)
			(end 0.12065 -0.2794)
			(stroke
				(width 0.1)
				(type default)
			)
			(layer "F.Fab")
		)
		(fp_line
			(start -0.12065 -0.305054)
			(end -0.12065 -0.2794)
			(stroke
				(width 0.1)
				(type default)
			)
			(layer "F.Fab")
		)
		(fp_line
			(start -0.67945 0.3048)
			(end -0.67945 -0.305054)
			(stroke
				(width 0.1)
				(type default)
			)
			(layer "F.Fab")
		)
		(fp_line
			(start -0.67945 -0.305054)
			(end -0.12065 -0.305054)
			(stroke
				(width 0.1)
				(type default)
			)
			(layer "F.Fab")
		)
		(pad "1" smd circle
			(at -0.40005 0 180)
			(size 0 0)
			(layers "F.Cu" "F.Mask" "F.Paste")
			(net "PVDD11_S3_P1_PMALERT")
		)
		(pad "2" smd circle
			(at 0.40005 0 180)
			(size 0 0)
			(layers "F.Cu" "F.Mask" "F.Paste")
			(net "GND")
		)
	)
	(footprint ""
		(layer "F.Cu")
		(at 173.08576 -351.825052)
		(property "Reference" "H22"
			(at -3.9116 -3.96113 0)
			(unlocked yes)
			(layer "F.SilkS")
			(effects
				(font
					(size 0.7874 0.5842)
					(thickness 0.1524)
				)
				(justify left)
			)
		)
		(property "Value" ""
			(at 0 0 0)
			(layer "F.Fab")
			(effects
				(font
					(size 1.27 1.27)
				)
			)
		)
		(duplicate_pad_numbers_are_jumpers no)
		(pad "1" thru_hole circle
			(at 0 0)
			(size 6.1976 6.1976)
			(drill 3.7338)
			(layers "*.Cu" "*.Mask")
			(remove_unused_layers no)
			(net "GND")
			(clearance -0.9779)
			(padstack
				(mode front_inner_back)
				(layer "Inner"
					(shape circle)
					(size 5.5372 5.5372)
					(clearance -0.6477)
				)
				(layer "B.Cu"
					(shape circle)
					(size 6.1976 6.1976)
					(clearance -0.9779)
				)
			)
		)
	)
)
